(kicad_pcb
	(version 20260206)
	(generator "pcbnew")
	(generator_version "10.0")
	(general
		(thickness 1.6)
		(legacy_teardrops no)
	)
	(paper "A4")
	(title_block
		(title "dpb — 14545-sa.0730WZS0815.brd")
		(comment 1 "Honey Badger (Wiwynn) / footprints 475-482 of 1066")
	)
	(layers
		(0 "F.Cu" signal "TOP")
		(4 "In1.Cu" signal "L2GND")
		(6 "In2.Cu" signal "L3")
		(8 "In3.Cu" signal "L4VCC")
		(10 "In4.Cu" signal "L5VCC")
		(12 "In5.Cu" signal "L6")
		(14 "In6.Cu" signal "L7GND")
		(2 "B.Cu" signal "BOTTOM")
		(9 "F.Adhes" user "F.Adhesive")
		(11 "B.Adhes" user "B.Adhesive")
		(13 "F.Paste" user "Package Geometry/Pastemask Top")
		(15 "B.Paste" user "Package Geometry/Pastemask Bottom")
		(5 "F.SilkS" user "Ref Des/Silkscreen Top")
		(7 "B.SilkS" user "Ref Des/Silkscreen Bottom")
		(1 "F.Mask" user "Board Geometry/Soldermask Top")
		(3 "B.Mask" user "Board Geometry/Soldermask Bottom")
		(17 "Dwgs.User" user "User.Drawings")
		(19 "Cmts.User" user "User.Comments")
		(21 "Eco1.User" user "User.Eco1")
		(23 "Eco2.User" user "User.Eco2")
		(25 "Edge.Cuts" user "Board Geometry/Outline")
		(27 "Margin" user)
		(31 "F.CrtYd" user "Package Geometry/Place Bound Top")
		(29 "B.CrtYd" user "Package Geometry/Place Bound Bottom")
		(35 "F.Fab" user "Ref Des/Assembly Top")
		(33 "B.Fab" user "Ref Des/Assembly Bottom")
	)
	(footprint ""
		(layer "F.Cu")
		(at 221.360746 -347.3577 -90)
		(property "Reference" "R118"
			(at 0 0 270)
			(layer "F.SilkS")
			(hide yes)
			(effects
				(font
					(size 1.27 1.27)
				)
			)
		)
		(property "Value" "0R2J-2-GP"
			(at 0.064008 -3.993896 270)
			(unlocked yes)
			(layer "F.Fab")
			(hide yes)
			(effects
				(font
					(size 1.016 1.016)
					(thickness 0.1524)
				)
			)
		)
		(property "Device Type" "R402H16"
			(at 0.064008 -5.517896 270)
			(unlocked yes)
			(layer "F.Fab")
			(hide yes)
			(effects
				(font
					(size 1.016 1.016)
					(thickness 0.1524)
				)
			)
		)
		(duplicate_pad_numbers_are_jumpers no)
		(fp_line
			(start -0.508 -0.9398)
			(end -0.508 0.9398)
			(stroke
				(width 0.1524)
				(type default)
			)
			(layer "F.SilkS")
		)
		(fp_line
			(start 0.508 -0.9398)
			(end -0.508 -0.9398)
			(stroke
				(width 0.1524)
				(type default)
			)
			(layer "F.SilkS")
		)
		(fp_rect
			(start -0.508 0.9398)
			(end 0.508 -0.9398)
			(stroke
				(width 0)
				(type default)
			)
			(fill no)
			(layer "F.CrtYd")
		)
		(fp_rect
			(start -0.508 0.9398)
			(end 0.508 -0.9398)
			(stroke
				(width 0)
				(type default)
			)
			(fill no)
			(layer "F.Fab")
		)
		(pad "1" smd custom
			(at 0 -0.4445 270)
			(size 0.1397 0.1397)
			(layers "F.Cu" "F.Mask" "F.Paste")
			(net "FLT_NET_HDD1")
			(options
				(clearance outline)
				(anchor circle)
			)
			(primitives
				(gr_poly
					(pts
						(arc
							(start -0.1778 -0.2794)
							(mid -0.249642 -0.249642)
							(end -0.2794 -0.1778)
						)
						(arc
							(start -0.2794 0.1778)
							(mid -0.249642 0.249642)
							(end -0.1778 0.2794)
						)
						(arc
							(start 0.1778 0.2794)
							(mid 0.249642 0.249642)
							(end 0.2794 0.1778)
						)
						(arc
							(start 0.2794 -0.1778)
							(mid 0.249642 -0.249642)
							(end 0.1778 -0.2794)
						)
					)
					(width 0)
					(fill yes)
				)
			)
		)
		(pad "2" smd custom
			(at 0 0.4445 270)
			(size 0.1397 0.1397)
			(layers "F.Cu" "F.Mask" "F.Paste")
			(net "FLT_HDD1_DRIVE")
			(options
				(clearance outline)
				(anchor circle)
			)
			(primitives
				(gr_poly
					(pts
						(arc
							(start -0.1778 -0.2794)
							(mid -0.249642 -0.249642)
							(end -0.2794 -0.1778)
						)
						(arc
							(start -0.2794 0.1778)
							(mid -0.249642 0.249642)
							(end -0.1778 0.2794)
						)
						(arc
							(start 0.1778 0.2794)
							(mid 0.249642 0.249642)
							(end 0.2794 0.1778)
						)
						(arc
							(start 0.2794 -0.1778)
							(mid 0.249642 -0.249642)
							(end 0.1778 -0.2794)
						)
					)
					(width 0)
					(fill yes)
				)
			)
		)
	)
	(footprint ""
		(layer "F.Cu")
		(at 40.385746 -116.487702)
		(property "Reference" "C318"
			(at 0 0 0)
			(layer "F.SilkS")
			(hide yes)
			(effects
				(font
					(size 1.27 1.27)
				)
			)
		)
		(property "Value" "SC10U25V6KX-1GP"
			(at -0.0762 -5.1308 0)
			(unlocked yes)
			(layer "F.Fab")
			(hide yes)
			(effects
				(font
					(size 1.016 1.016)
					(thickness 0.1524)
				)
			)
		)
		(property "Device Type" "C1206H71"
			(at -0.127 -6.6548 0)
			(unlocked yes)
			(layer "F.Fab")
			(hide yes)
			(effects
				(font
					(size 1.016 1.016)
					(thickness 0.1524)
				)
			)
		)
		(duplicate_pad_numbers_are_jumpers no)
		(fp_line
			(start -1.016 -2.2352)
			(end 1.016 -2.2352)
			(stroke
				(width 0.1524)
				(type default)
			)
			(layer "F.SilkS")
		)
		(fp_line
			(start -1.016 -0.8382)
			(end -1.016 -2.2352)
			(stroke
				(width 0.1524)
				(type default)
			)
			(layer "F.SilkS")
		)
		(fp_line
			(start -1.016 2.2352)
			(end -1.016 0.8382)
			(stroke
				(width 0.1524)
				(type default)
			)
			(layer "F.SilkS")
		)
		(fp_line
			(start 1.016 -2.2352)
			(end 1.016 -0.8382)
			(stroke
				(width 0.1524)
				(type default)
			)
			(layer "F.SilkS")
		)
		(fp_line
			(start 1.016 0.8382)
			(end 1.016 2.2352)
			(stroke
				(width 0.1524)
				(type default)
			)
			(layer "F.SilkS")
		)
		(fp_line
			(start 1.016 2.2352)
			(end -1.016 2.2352)
			(stroke
				(width 0.1524)
				(type default)
			)
			(layer "F.SilkS")
		)
		(fp_rect
			(start -1.0922 2.3114)
			(end 1.0922 -2.3114)
			(stroke
				(width 0)
				(type default)
			)
			(fill no)
			(layer "F.CrtYd")
		)
		(fp_poly
			(pts
				(xy 1.0922 -2.3114) (xy 1.0922 2.3114) (xy -1.0922 2.3114) (xy -1.0922 -2.3114)
			)
			(stroke
				(width 0)
				(type default)
			)
			(fill no)
			(layer "F.Fab")
		)
		(pad "1" smd rect
			(at 0 -1.397)
			(size 1.651 1.27)
			(layers "F.Cu" "F.Mask" "F.Paste")
			(net "P12V_HDD13")
		)
		(pad "2" smd rect
			(at 0 1.397)
			(size 1.651 1.27)
			(layers "F.Cu" "F.Mask" "F.Paste")
			(net "GND")
		)
	)
	(footprint ""
		(layer "F.Cu")
		(at 41.274746 -225.834702)
		(property "Reference" "C298"
			(at 0 0 0)
			(layer "F.SilkS")
			(hide yes)
			(effects
				(font
					(size 1.27 1.27)
				)
			)
		)
		(property "Value" "SC1U16V3KX-5GP"
			(at 0 -2.8194 0)
			(unlocked yes)
			(layer "F.Fab")
			(hide yes)
			(effects
				(font
					(size 1.016 1.016)
					(thickness 0.1524)
				)
			)
		)
		(property "Device Type" "C603H36"
			(at 0 -4.3434 0)
			(unlocked yes)
			(layer "F.Fab")
			(hide yes)
			(effects
				(font
					(size 1.016 1.016)
					(thickness 0.1524)
				)
			)
		)
		(duplicate_pad_numbers_are_jumpers no)
		(fp_line
			(start 0.508 0)
			(end -0.508 0)
			(stroke
				(width 0.2032)
				(type default)
			)
			(layer "F.SilkS")
		)
		(fp_rect
			(start -0.5842 1.3335)
			(end 0.5842 -1.3335)
			(stroke
				(width 0)
				(type default)
			)
			(fill no)
			(layer "F.CrtYd")
		)
		(fp_rect
			(start -0.5842 1.3335)
			(end 0.5842 -1.3335)
			(stroke
				(width 0)
				(type default)
			)
			(fill no)
			(layer "F.Fab")
		)
		(pad "1" smd custom
			(at 0 -0.762)
			(size 0.2159 0.2159)
			(layers "F.Cu" "F.Mask" "F.Paste")
			(net "P5V_HDD12")
			(options
				(clearance outline)
				(anchor circle)
			)
			(primitives
				(gr_poly
					(pts
						(arc
							(start -0.3302 -0.4318)
							(mid -0.402042 -0.402042)
							(end -0.4318 -0.3302)
						)
						(arc
							(start -0.4318 0.3302)
							(mid -0.402042 0.402042)
							(end -0.3302 0.4318)
						)
						(arc
							(start 0.3302 0.4318)
							(mid 0.402042 0.402042)
							(end 0.4318 0.3302)
						)
						(arc
							(start 0.4318 -0.3302)
							(mid 0.402042 -0.402042)
							(end 0.3302 -0.4318)
						)
					)
					(width 0)
					(fill yes)
				)
			)
		)
		(pad "2" smd custom
			(at 0 0.762)
			(size 0.2159 0.2159)
			(layers "F.Cu" "F.Mask" "F.Paste")
			(net "GND")
			(options
				(clearance outline)
				(anchor circle)
			)
			(primitives
				(gr_poly
					(pts
						(arc
							(start -0.3302 -0.4318)
							(mid -0.402042 -0.402042)
							(end -0.4318 -0.3302)
						)
						(arc
							(start -0.4318 0.3302)
							(mid -0.402042 0.402042)
							(end -0.3302 0.4318)
						)
						(arc
							(start 0.3302 0.4318)
							(mid 0.402042 0.402042)
							(end 0.4318 0.3302)
						)
						(arc
							(start 0.4318 -0.3302)
							(mid 0.402042 -0.402042)
							(end 0.3302 -0.4318)
						)
					)
					(width 0)
					(fill yes)
				)
			)
		)
	)
	(footprint ""
		(layer "F.Cu")
		(at 7.619746 -215.81364)
		(property "Reference" "TP17"
			(at 0 0 0)
			(layer "F.SilkS")
			(hide yes)
			(effects
				(font
					(size 1.27 1.27)
				)
			)
		)
		(property "Value" "TPAD32-GP"
			(at 0 -3.166364 0)
			(unlocked yes)
			(layer "F.Fab")
			(hide yes)
			(effects
				(font
					(size 1.016 1.016)
					(thickness 0.1524)
				)
			)
		)
		(property "Device Type" "TPAD32"
			(at 0 -4.690618 0)
			(unlocked yes)
			(layer "F.Fab")
			(hide yes)
			(effects
				(font
					(size 1.016 1.016)
					(thickness 0.1524)
				)
			)
		)
		(duplicate_pad_numbers_are_jumpers no)
		(fp_poly
			(pts
				(arc
					(start 0.4064 0)
					(mid -0.4064 0)
					(end 0.4064 0)
				)
			)
			(stroke
				(width 0)
				(type default)
			)
			(fill no)
			(layer "F.CrtYd")
		)
		(fp_poly
			(pts
				(arc
					(start 0.7112 0)
					(mid -0.7112 0)
					(end 0.7112 0)
				)
			)
			(stroke
				(width 0)
				(type default)
			)
			(fill no)
			(layer "F.Fab")
		)
		(pad "1" smd circle
			(at 0 0)
			(size 0.8128 0.8128)
			(layers "F.Cu" "F.Mask" "F.Paste")
			(net "SAS_EXP_B_PWR15")
		)
	)
	(footprint ""
		(layer "F.Cu")
		(at 67.507358 -488.871514 -90)
		(property "Reference" "Q11"
			(at 0 0 270)
			(layer "F.SilkS")
			(hide yes)
			(effects
				(font
					(size 1.27 1.27)
				)
			)
		)
		(property "Value" "AO4406AL-GP"
			(at -3.707384 -1.5367 270)
			(unlocked yes)
			(layer "F.Fab")
			(hide yes)
			(effects
				(font
					(size 1.016 1.016)
					(thickness 0.1524)
				)
			)
		)
		(property "Device Type" "SOIC8H69"
			(at -3.707384 -3.0607 270)
			(unlocked yes)
			(layer "F.Fab")
			(hide yes)
			(effects
				(font
					(size 1.016 1.016)
					(thickness 0.1524)
				)
			)
		)
		(duplicate_pad_numbers_are_jumpers no)
		(fp_line
			(start -2.6289 3.4417)
			(end -2.6289 1.4732)
			(stroke
				(width 0.381)
				(type default)
			)
			(layer "F.SilkS")
		)
		(fp_line
			(start -2.7432 1.4224)
			(end -2.6416 1.4224)
			(stroke
				(width 0.1524)
				(type default)
			)
			(layer "F.SilkS")
		)
		(fp_line
			(start -2.7432 1.4224)
			(end 2.1336 1.4224)
			(stroke
				(width 0.1524)
				(type default)
			)
			(layer "F.SilkS")
		)
		(fp_line
			(start 2.1336 1.4224)
			(end 2.1336 -1.4224)
			(stroke
				(width 0.1524)
				(type default)
			)
			(layer "F.SilkS")
		)
		(fp_line
			(start -2.1844 -0.0508)
			(end -2.7178 0.508)
			(stroke
				(width 0.1524)
				(type default)
			)
			(layer "F.SilkS")
		)
		(fp_line
			(start -2.7178 -0.508)
			(end -2.1844 -0.0508)
			(stroke
				(width 0.1524)
				(type default)
			)
			(layer "F.SilkS")
		)
		(fp_line
			(start -2.7432 -1.4224)
			(end -2.7432 1.4224)
			(stroke
				(width 0.1524)
				(type default)
			)
			(layer "F.SilkS")
		)
		(fp_line
			(start 2.1336 -1.4224)
			(end -2.7432 -1.4224)
			(stroke
				(width 0.1524)
				(type default)
			)
			(layer "F.SilkS")
		)
		(fp_poly
			(pts
				(xy -2.2098 -1.4224) (xy -2.2098 1.4224) (xy 2.2098 1.4224) (xy 2.2098 -1.4224)
			)
			(stroke
				(width 0)
				(type default)
			)
			(fill yes)
			(layer "F.SilkS")
		)
		(fp_rect
			(start -2.450084 2.999994)
			(end 2.450084 -2.999994)
			(stroke
				(width 0)
				(type default)
			)
			(fill no)
			(layer "F.CrtYd")
		)
		(fp_poly
			(pts
				(xy -2.8194 3.6322) (xy -2.8194 -3.6322) (xy 2.8194 -3.6322) (xy 2.8194 1.18364) (xy 2.450084 1.18364)
				(xy 2.450084 -2.999994) (xy -2.450084 -2.999994) (xy -2.450084 2.999994) (xy 2.450084 2.999994)
				(xy 2.450084 1.18618) (xy 2.8194 1.18618) (xy 2.8194 3.6322)
			)
			(stroke
				(width 0)
				(type default)
			)
			(fill no)
			(layer "F.CrtYd")
		)
		(fp_rect
			(start -2.8194 3.6322)
			(end 2.8194 -3.6322)
			(stroke
				(width 0)
				(type default)
			)
			(fill no)
			(layer "F.Fab")
		)
		(pad "1" smd rect
			(at -1.905 2.54 270)
			(size 0.635 1.651)
			(layers "F.Cu" "F.Mask" "F.Paste")
			(net "P5V_HDD5")
		)
		(pad "2" smd rect
			(at -0.635 2.54 270)
			(size 0.635 1.651)
			(layers "F.Cu" "F.Mask" "F.Paste")
			(net "P5V_HDD5")
		)
		(pad "3" smd rect
			(at 0.635 2.54 270)
			(size 0.635 1.651)
			(layers "F.Cu" "F.Mask" "F.Paste")
			(net "P5V_HDD5")
		)
		(pad "4" smd rect
			(at 1.905 2.54 270)
			(size 0.635 1.651)
			(layers "F.Cu" "F.Mask" "F.Paste")
			(net "SW_HDD5_P")
		)
		(pad "5" smd rect
			(at 1.905 -2.54 270)
			(size 0.635 1.651)
			(layers "F.Cu" "F.Mask" "F.Paste")
			(net "P5VB")
		)
		(pad "6" smd rect
			(at 0.635 -2.54 270)
			(size 0.635 1.651)
			(layers "F.Cu" "F.Mask" "F.Paste")
			(net "P5VB")
		)
		(pad "7" smd rect
			(at -0.635 -2.54 270)
			(size 0.635 1.651)
			(layers "F.Cu" "F.Mask" "F.Paste")
			(net "P5VB")
		)
		(pad "8" smd rect
			(at -1.905 -2.54 270)
			(size 0.635 1.651)
			(layers "F.Cu" "F.Mask" "F.Paste")
			(net "P5VB")
		)
	)
	(footprint ""
		(layer "F.Cu")
		(at 39.623746 -143.7767 90)
		(property "Reference" "R215"
			(at 0 0 90)
			(layer "F.SilkS")
			(hide yes)
			(effects
				(font
					(size 1.27 1.27)
				)
			)
		)
		(property "Value" "330R2F-GP"
			(at 0.064008 -3.993896 90)
			(unlocked yes)
			(layer "F.Fab")
			(hide yes)
			(effects
				(font
					(size 1.016 1.016)
					(thickness 0.1524)
				)
			)
		)
		(property "Device Type" "R402H16"
			(at 0.064008 -5.517896 90)
			(unlocked yes)
			(layer "F.Fab")
			(hide yes)
			(effects
				(font
					(size 1.016 1.016)
					(thickness 0.1524)
				)
			)
		)
		(duplicate_pad_numbers_are_jumpers no)
		(fp_line
			(start 0.508 -0.9398)
			(end -0.508 -0.9398)
			(stroke
				(width 0.1524)
				(type default)
			)
			(layer "F.SilkS")
		)
		(fp_line
			(start -0.508 -0.9398)
			(end -0.508 0.9398)
			(stroke
				(width 0.1524)
				(type default)
			)
			(layer "F.SilkS")
		)
		(fp_rect
			(start -0.508 0.9398)
			(end 0.508 -0.9398)
			(stroke
				(width 0)
				(type default)
			)
			(fill no)
			(layer "F.CrtYd")
		)
		(fp_rect
			(start -0.508 0.9398)
			(end 0.508 -0.9398)
			(stroke
				(width 0)
				(type default)
			)
			(fill no)
			(layer "F.Fab")
		)
		(pad "1" smd custom
			(at 0 -0.4445 90)
			(size 0.1397 0.1397)
			(layers "F.Cu" "F.Mask" "F.Paste")
			(net "P3V3_HDD8_LED")
			(options
				(clearance outline)
				(anchor circle)
			)
			(primitives
				(gr_poly
					(pts
						(arc
							(start -0.1778 -0.2794)
							(mid -0.249642 -0.249642)
							(end -0.2794 -0.1778)
						)
						(arc
							(start -0.2794 0.1778)
							(mid -0.249642 0.249642)
							(end -0.1778 0.2794)
						)
						(arc
							(start 0.1778 0.2794)
							(mid 0.249642 0.249642)
							(end 0.2794 0.1778)
						)
						(arc
							(start 0.2794 -0.1778)
							(mid 0.249642 -0.249642)
							(end 0.1778 -0.2794)
						)
					)
					(width 0)
					(fill yes)
				)
			)
		)
		(pad "2" smd custom
			(at 0 0.4445 90)
			(size 0.1397 0.1397)
			(layers "F.Cu" "F.Mask" "F.Paste")
			(net "FLT_HDD8")
			(options
				(clearance outline)
				(anchor circle)
			)
			(primitives
				(gr_poly
					(pts
						(arc
							(start -0.1778 -0.2794)
							(mid -0.249642 -0.249642)
							(end -0.2794 -0.1778)
						)
						(arc
							(start -0.2794 0.1778)
							(mid -0.249642 0.249642)
							(end -0.1778 0.2794)
						)
						(arc
							(start 0.1778 0.2794)
							(mid 0.249642 0.249642)
							(end 0.2794 0.1778)
						)
						(arc
							(start 0.2794 -0.1778)
							(mid 0.249642 -0.249642)
							(end 0.1778 -0.2794)
						)
					)
					(width 0)
					(fill yes)
				)
			)
		)
	)
	(footprint ""
		(layer "F.Cu")
		(at 227.499926 -247.160034 180)
		(property "Reference" "LED3"
			(at 0 0 180)
			(layer "F.SilkS")
			(hide yes)
			(effects
				(font
					(size 1.27 1.27)
				)
			)
		)
		(property "Value" "LED-RB-4-GP"
			(at 5.88899 1.80848 180)
			(unlocked yes)
			(layer "F.Fab")
			(hide yes)
			(effects
				(font
					(size 1.016 1.016)
					(thickness 0.1524)
				)
			)
		)
		(property "Device Type" "LED1613-4PH20"
			(at 5.88899 0.28448 180)
			(unlocked yes)
			(layer "F.Fab")
			(hide yes)
			(effects
				(font
					(size 1.016 1.016)
					(thickness 0.1524)
				)
			)
		)
		(duplicate_pad_numbers_are_jumpers no)
		(fp_line
			(start 1.4478 0.9652)
			(end -1.4478 0.9652)
			(stroke
				(width 0.1524)
				(type default)
			)
			(layer "F.SilkS")
		)
		(fp_line
			(start 1.4478 -0.9652)
			(end 1.4478 0.9652)
			(stroke
				(width 0.1524)
				(type default)
			)
			(layer "F.SilkS")
		)
		(fp_line
			(start -1.4478 0.9652)
			(end -1.4478 -0.9652)
			(stroke
				(width 0.1524)
				(type default)
			)
			(layer "F.SilkS")
		)
		(fp_line
			(start -1.4478 0.9652)
			(end -1.4478 -0.9652)
			(stroke
				(width 0.508)
				(type default)
			)
			(layer "F.SilkS")
		)
		(fp_line
			(start -1.4478 -0.9652)
			(end 1.4478 -0.9652)
			(stroke
				(width 0.1524)
				(type default)
			)
			(layer "F.SilkS")
		)
		(fp_rect
			(start -0.8001 0.6477)
			(end 0.8001 -0.6477)
			(stroke
				(width 0)
				(type default)
			)
			(fill no)
			(layer "F.CrtYd")
		)
		(fp_poly
			(pts
				(xy -1.7018 1.2192) (xy -1.7018 -0.06223) (xy -0.8001 -0.06223) (xy -0.8001 0.6477) (xy 0.8001 0.6477)
				(xy 0.8001 -0.6477) (xy -0.8001 -0.6477) (xy -0.8001 -0.0635) (xy -1.7018 -0.0635) (xy -1.7018 -1.2192)
				(xy 1.7018 -1.2192) (xy 1.7018 1.2192)
			)
			(stroke
				(width 0)
				(type default)
			)
			(fill no)
			(layer "F.CrtYd")
		)
		(fp_rect
			(start -1.7018 1.2192)
			(end 1.7018 -1.2192)
			(stroke
				(width 0)
				(type default)
			)
			(fill no)
			(layer "F.Fab")
		)
		(pad "1" smd rect
			(at -0.73025 0.4064 180)
			(size 0.9144 0.6096)
			(layers "F.Cu" "F.Mask" "F.Paste")
			(net "DRV_ACT_NET2")
		)
		(pad "2" smd rect
			(at -0.73025 -0.4064 180)
			(size 0.9144 0.6096)
			(layers "F.Cu" "F.Mask" "F.Paste")
			(net "FLT_NET_HDD2")
		)
		(pad "3" smd rect
			(at 0.73025 -0.4064 180)
			(size 0.9144 0.6096)
			(layers "F.Cu" "F.Mask" "F.Paste")
			(net "FLT_HDD2")
		)
		(pad "4" smd rect
			(at 0.73025 0.4064 180)
			(size 0.9144 0.6096)
			(layers "F.Cu" "F.Mask" "F.Paste")
			(net "DRV_ACT_2")
		)
	)
	(footprint ""
		(layer "F.Cu")
		(at 204.850746 -483.5017)
		(property "Reference" "TP25"
			(at 0 0 0)
			(layer "F.SilkS")
			(hide yes)
			(effects
				(font
					(size 1.27 1.27)
				)
			)
		)
		(property "Value" "TPAD32-GP"
			(at 0 -3.166364 0)
			(unlocked yes)
			(layer "F.Fab")
			(hide yes)
			(effects
				(font
					(size 1.016 1.016)
					(thickness 0.1524)
				)
			)
		)
		(property "Device Type" "TPAD32"
			(at 0 -4.690618 0)
			(unlocked yes)
			(layer "F.Fab")
			(hide yes)
			(effects
				(font
					(size 1.016 1.016)
					(thickness 0.1524)
				)
			)
		)
		(duplicate_pad_numbers_are_jumpers no)
		(fp_poly
			(pts
				(arc
					(start 0.4064 0)
					(mid -0.4064 0)
					(end 0.4064 0)
				)
			)
			(stroke
				(width 0)
				(type default)
			)
			(fill no)
			(layer "F.CrtYd")
		)
		(fp_poly
			(pts
				(arc
					(start 0.7112 0)
					(mid -0.7112 0)
					(end 0.7112 0)
				)
			)
			(stroke
				(width 0)
				(type default)
			)
			(fill no)
			(layer "F.Fab")
		)
		(pad "1" smd circle
			(at 0 0)
			(size 0.8128 0.8128)
			(layers "F.Cu" "F.Mask" "F.Paste")
			(net "ACT_HDD0")
		)
	)
)
